(kicad_pcb
	(version 20260206)
	(generator "pcbnew")
	(generator_version "10.0")
	(general
		(thickness 1.6)
		(legacy_teardrops no)
	)
	(paper "A4")
	(title_block
		(title "03242023_DA0F0TMBIJ0_F0T_Motherboard_J_brd_V01_OCP.brd")
		(comment 1 "Grand Teton / footprints 2001-2007 of 6105")
	)
	(layers
		(0 "F.Cu" signal "TOP")
		(4 "In1.Cu" signal "GND")
		(6 "In2.Cu" signal "IN1")
		(8 "In3.Cu" signal "GND1")
		(10 "In4.Cu" signal "IN2")
		(12 "In5.Cu" signal "GND2")
		(14 "In6.Cu" signal "IN3")
		(16 "In7.Cu" signal "GND3")
		(18 "In8.Cu" signal "VCC")
		(20 "In9.Cu" signal "VCC1")
		(22 "In10.Cu" signal "GND4")
		(24 "In11.Cu" signal "IN4")
		(26 "In12.Cu" signal "GND5")
		(28 "In13.Cu" signal "IN5")
		(30 "In14.Cu" signal "GND6")
		(32 "In15.Cu" signal "IN6")
		(34 "In16.Cu" signal "GND7")
		(2 "B.Cu" signal "BOTTOM")
		(9 "F.Adhes" user "F.Adhesive")
		(11 "B.Adhes" user "B.Adhesive")
		(13 "F.Paste" user "Package Geometry/Pastemask Top")
		(15 "B.Paste" user "Package Geometry/Pastemask Bottom")
		(5 "F.SilkS" user "Ref Des/Silkscreen Top")
		(7 "B.SilkS" user "Ref Des/Silkscreen Bottom")
		(1 "F.Mask" user "Board Geometry/Soldermask Top")
		(3 "B.Mask" user "Board Geometry/Soldermask Bottom")
		(17 "Dwgs.User" user "User.Drawings")
		(19 "Cmts.User" user "User.Comments")
		(21 "Eco1.User" user "User.Eco1")
		(23 "Eco2.User" user "User.Eco2")
		(25 "Edge.Cuts" user "Board Geometry/Outline")
		(27 "Margin" user)
		(31 "F.CrtYd" user "Package Geometry/Place Bound Top")
		(29 "B.CrtYd" user "Package Geometry/Place Bound Bottom")
		(35 "F.Fab" user "Ref Des/Assembly Top")
		(33 "B.Fab" user "Ref Des/Assembly Bottom")
	)
	(footprint ""
		(layer "F.Cu")
		(at 101.58349 -333.525368 -90)
		(property "Reference" "PC558_P1_2"
			(at 0 0 270)
			(layer "F.SilkS")
			(hide yes)
			(effects
				(font
					(size 1.27 1.27)
				)
			)
		)
		(property "Value" ""
			(at 0 0 270)
			(layer "F.Fab")
			(effects
				(font
					(size 1.27 1.27)
				)
			)
		)
		(duplicate_pad_numbers_are_jumpers no)
		(fp_line
			(start -0.7874 0.4064)
			(end -0.7874 -0.4064)
			(stroke
				(width 0.1524)
				(type default)
			)
			(layer "F.SilkS")
		)
		(fp_line
			(start 0.7874 0.4064)
			(end -0.7874 0.4064)
			(stroke
				(width 0.1524)
				(type default)
			)
			(layer "F.SilkS")
		)
		(fp_line
			(start -0.7874 -0.4064)
			(end 0.7874 -0.4064)
			(stroke
				(width 0.1524)
				(type default)
			)
			(layer "F.SilkS")
		)
		(fp_line
			(start 0.7874 -0.4064)
			(end 0.7874 0.4064)
			(stroke
				(width 0.1524)
				(type default)
			)
			(layer "F.SilkS")
		)
		(fp_line
			(start -0.67945 0.3048)
			(end -0.67945 -0.305054)
			(stroke
				(width 0.1)
				(type default)
			)
			(layer "F.Fab")
		)
		(fp_line
			(start -0.12065 0.3048)
			(end -0.67945 0.3048)
			(stroke
				(width 0.1)
				(type default)
			)
			(layer "F.Fab")
		)
		(fp_line
			(start 0.120396 0.3048)
			(end 0.120396 0.2794)
			(stroke
				(width 0.1)
				(type default)
			)
			(layer "F.Fab")
		)
		(fp_line
			(start 0.67945 0.3048)
			(end 0.120396 0.3048)
			(stroke
				(width 0.1)
				(type default)
			)
			(layer "F.Fab")
		)
		(fp_line
			(start -0.12065 0.2794)
			(end -0.12065 0.3048)
			(stroke
				(width 0.1)
				(type default)
			)
			(layer "F.Fab")
		)
		(fp_line
			(start 0.120396 0.2794)
			(end -0.12065 0.2794)
			(stroke
				(width 0.1)
				(type default)
			)
			(layer "F.Fab")
		)
		(fp_line
			(start -0.12065 -0.2794)
			(end 0.12065 -0.2794)
			(stroke
				(width 0.1)
				(type default)
			)
			(layer "F.Fab")
		)
		(fp_line
			(start 0.12065 -0.2794)
			(end 0.12065 -0.3048)
			(stroke
				(width 0.1)
				(type default)
			)
			(layer "F.Fab")
		)
		(fp_line
			(start 0.12065 -0.3048)
			(end 0.67945 -0.3048)
			(stroke
				(width 0.1)
				(type default)
			)
			(layer "F.Fab")
		)
		(fp_line
			(start 0.67945 -0.3048)
			(end 0.67945 0.3048)
			(stroke
				(width 0.1)
				(type default)
			)
			(layer "F.Fab")
		)
		(fp_line
			(start -0.67945 -0.305054)
			(end -0.12065 -0.305054)
			(stroke
				(width 0.1)
				(type default)
			)
			(layer "F.Fab")
		)
		(fp_line
			(start -0.12065 -0.305054)
			(end -0.12065 -0.2794)
			(stroke
				(width 0.1)
				(type default)
			)
			(layer "F.Fab")
		)
		(pad "1" smd circle
			(at -0.40005 0 270)
			(size 0 0)
			(layers "F.Cu" "F.Mask" "F.Paste")
			(net "PVCCIN_CPU1_PVCC")
		)
		(pad "2" smd circle
			(at 0.40005 0 270)
			(size 0 0)
			(layers "F.Cu" "F.Mask" "F.Paste")
			(net "GND")
		)
	)
	(footprint ""
		(layer "F.Cu")
		(at 424.204892 -382.361948 180)
		(property "Reference" "R2829"
			(at 0 0 180)
			(layer "F.SilkS")
			(hide yes)
			(effects
				(font
					(size 1.27 1.27)
				)
			)
		)
		(property "Value" ""
			(at 0 0 180)
			(layer "F.Fab")
			(effects
				(font
					(size 1.27 1.27)
				)
			)
		)
		(duplicate_pad_numbers_are_jumpers no)
		(fp_line
			(start 0.7874 0.4064)
			(end -0.7874 0.4064)
			(stroke
				(width 0.1524)
				(type default)
			)
			(layer "F.SilkS")
		)
		(fp_line
			(start 0.7874 -0.4064)
			(end 0.7874 0.4064)
			(stroke
				(width 0.1524)
				(type default)
			)
			(layer "F.SilkS")
		)
		(fp_line
			(start -0.7874 0.4064)
			(end -0.7874 -0.4064)
			(stroke
				(width 0.1524)
				(type default)
			)
			(layer "F.SilkS")
		)
		(fp_line
			(start -0.7874 -0.4064)
			(end 0.7874 -0.4064)
			(stroke
				(width 0.1524)
				(type default)
			)
			(layer "F.SilkS")
		)
		(fp_line
			(start 0.67945 0.3048)
			(end 0.120396 0.3048)
			(stroke
				(width 0.1)
				(type default)
			)
			(layer "F.Fab")
		)
		(fp_line
			(start 0.67945 -0.3048)
			(end 0.67945 0.3048)
			(stroke
				(width 0.1)
				(type default)
			)
			(layer "F.Fab")
		)
		(fp_line
			(start 0.12065 -0.2794)
			(end 0.12065 -0.3048)
			(stroke
				(width 0.1)
				(type default)
			)
			(layer "F.Fab")
		)
		(fp_line
			(start 0.12065 -0.3048)
			(end 0.67945 -0.3048)
			(stroke
				(width 0.1)
				(type default)
			)
			(layer "F.Fab")
		)
		(fp_line
			(start 0.120396 0.3048)
			(end 0.120396 0.2794)
			(stroke
				(width 0.1)
				(type default)
			)
			(layer "F.Fab")
		)
		(fp_line
			(start 0.120396 0.2794)
			(end -0.12065 0.2794)
			(stroke
				(width 0.1)
				(type default)
			)
			(layer "F.Fab")
		)
		(fp_line
			(start -0.12065 0.3048)
			(end -0.67945 0.3048)
			(stroke
				(width 0.1)
				(type default)
			)
			(layer "F.Fab")
		)
		(fp_line
			(start -0.12065 0.2794)
			(end -0.12065 0.3048)
			(stroke
				(width 0.1)
				(type default)
			)
			(layer "F.Fab")
		)
		(fp_line
			(start -0.12065 -0.2794)
			(end 0.12065 -0.2794)
			(stroke
				(width 0.1)
				(type default)
			)
			(layer "F.Fab")
		)
		(fp_line
			(start -0.12065 -0.305054)
			(end -0.12065 -0.2794)
			(stroke
				(width 0.1)
				(type default)
			)
			(layer "F.Fab")
		)
		(fp_line
			(start -0.67945 0.3048)
			(end -0.67945 -0.305054)
			(stroke
				(width 0.1)
				(type default)
			)
			(layer "F.Fab")
		)
		(fp_line
			(start -0.67945 -0.305054)
			(end -0.12065 -0.305054)
			(stroke
				(width 0.1)
				(type default)
			)
			(layer "F.Fab")
		)
		(pad "1" smd circle
			(at -0.40005 0 180)
			(size 0 0)
			(layers "F.Cu" "F.Mask" "F.Paste")
			(net "RST_BMC_FROM_SWB_N")
		)
		(pad "2" smd circle
			(at 0.40005 0 180)
			(size 0 0)
			(layers "F.Cu" "F.Mask" "F.Paste")
			(net "GND")
		)
	)
	(footprint ""
		(layer "F.Cu")
		(at 51.593496 -108.14177)
		(property "Reference" "R3727"
			(at 0 0 0)
			(layer "F.SilkS")
			(hide yes)
			(effects
				(font
					(size 1.27 1.27)
				)
			)
		)
		(property "Value" ""
			(at 0 0 0)
			(layer "F.Fab")
			(effects
				(font
					(size 1.27 1.27)
				)
			)
		)
		(duplicate_pad_numbers_are_jumpers no)
		(fp_line
			(start -0.7874 -0.4064)
			(end 0.7874 -0.4064)
			(stroke
				(width 0.1524)
				(type default)
			)
			(layer "F.SilkS")
		)
		(fp_line
			(start -0.7874 0.4064)
			(end -0.7874 -0.4064)
			(stroke
				(width 0.1524)
				(type default)
			)
			(layer "F.SilkS")
		)
		(fp_line
			(start 0.7874 -0.4064)
			(end 0.7874 0.4064)
			(stroke
				(width 0.1524)
				(type default)
			)
			(layer "F.SilkS")
		)
		(fp_line
			(start 0.7874 0.4064)
			(end -0.7874 0.4064)
			(stroke
				(width 0.1524)
				(type default)
			)
			(layer "F.SilkS")
		)
		(fp_line
			(start -0.67945 -0.305054)
			(end -0.12065 -0.305054)
			(stroke
				(width 0.1)
				(type default)
			)
			(layer "F.Fab")
		)
		(fp_line
			(start -0.67945 0.3048)
			(end -0.67945 -0.305054)
			(stroke
				(width 0.1)
				(type default)
			)
			(layer "F.Fab")
		)
		(fp_line
			(start -0.12065 -0.305054)
			(end -0.12065 -0.2794)
			(stroke
				(width 0.1)
				(type default)
			)
			(layer "F.Fab")
		)
		(fp_line
			(start -0.12065 -0.2794)
			(end 0.12065 -0.2794)
			(stroke
				(width 0.1)
				(type default)
			)
			(layer "F.Fab")
		)
		(fp_line
			(start -0.12065 0.2794)
			(end -0.12065 0.3048)
			(stroke
				(width 0.1)
				(type default)
			)
			(layer "F.Fab")
		)
		(fp_line
			(start -0.12065 0.3048)
			(end -0.67945 0.3048)
			(stroke
				(width 0.1)
				(type default)
			)
			(layer "F.Fab")
		)
		(fp_line
			(start 0.120396 0.2794)
			(end -0.12065 0.2794)
			(stroke
				(width 0.1)
				(type default)
			)
			(layer "F.Fab")
		)
		(fp_line
			(start 0.120396 0.3048)
			(end 0.120396 0.2794)
			(stroke
				(width 0.1)
				(type default)
			)
			(layer "F.Fab")
		)
		(fp_line
			(start 0.12065 -0.3048)
			(end 0.67945 -0.3048)
			(stroke
				(width 0.1)
				(type default)
			)
			(layer "F.Fab")
		)
		(fp_line
			(start 0.12065 -0.2794)
			(end 0.12065 -0.3048)
			(stroke
				(width 0.1)
				(type default)
			)
			(layer "F.Fab")
		)
		(fp_line
			(start 0.67945 -0.3048)
			(end 0.67945 0.3048)
			(stroke
				(width 0.1)
				(type default)
			)
			(layer "F.Fab")
		)
		(fp_line
			(start 0.67945 0.3048)
			(end 0.120396 0.3048)
			(stroke
				(width 0.1)
				(type default)
			)
			(layer "F.Fab")
		)
		(pad "1" smd circle
			(at -0.40005 0)
			(size 0 0)
			(layers "F.Cu" "F.Mask" "F.Paste")
			(net "P3V3_AUX")
		)
		(pad "2" smd circle
			(at 0.40005 0)
			(size 0 0)
			(layers "F.Cu" "F.Mask" "F.Paste")
			(net "SMB_LM75_1_3V3AUX_SCL")
		)
	)
	(footprint ""
		(layer "F.Cu")
		(at 49.496472 -436.803038)
		(property "Reference" "C1766"
			(at 0 0 0)
			(layer "F.SilkS")
			(hide yes)
			(effects
				(font
					(size 1.27 1.27)
				)
			)
		)
		(property "Value" ""
			(at 0 0 0)
			(layer "F.Fab")
			(effects
				(font
					(size 1.27 1.27)
				)
			)
		)
		(duplicate_pad_numbers_are_jumpers no)
		(fp_line
			(start -0.7874 -0.4064)
			(end 0.7874 -0.4064)
			(stroke
				(width 0.1524)
				(type default)
			)
			(layer "F.SilkS")
		)
		(fp_line
			(start -0.7874 0.4064)
			(end -0.7874 -0.4064)
			(stroke
				(width 0.1524)
				(type default)
			)
			(layer "F.SilkS")
		)
		(fp_line
			(start 0.7874 -0.4064)
			(end 0.7874 0.4064)
			(stroke
				(width 0.1524)
				(type default)
			)
			(layer "F.SilkS")
		)
		(fp_line
			(start 0.7874 0.4064)
			(end -0.7874 0.4064)
			(stroke
				(width 0.1524)
				(type default)
			)
			(layer "F.SilkS")
		)
		(fp_line
			(start -0.67945 -0.305054)
			(end -0.12065 -0.305054)
			(stroke
				(width 0.1)
				(type default)
			)
			(layer "F.Fab")
		)
		(fp_line
			(start -0.67945 0.3048)
			(end -0.67945 -0.305054)
			(stroke
				(width 0.1)
				(type default)
			)
			(layer "F.Fab")
		)
		(fp_line
			(start -0.12065 -0.305054)
			(end -0.12065 -0.2794)
			(stroke
				(width 0.1)
				(type default)
			)
			(layer "F.Fab")
		)
		(fp_line
			(start -0.12065 -0.2794)
			(end 0.12065 -0.2794)
			(stroke
				(width 0.1)
				(type default)
			)
			(layer "F.Fab")
		)
		(fp_line
			(start -0.12065 0.2794)
			(end -0.12065 0.3048)
			(stroke
				(width 0.1)
				(type default)
			)
			(layer "F.Fab")
		)
		(fp_line
			(start -0.12065 0.3048)
			(end -0.67945 0.3048)
			(stroke
				(width 0.1)
				(type default)
			)
			(layer "F.Fab")
		)
		(fp_line
			(start 0.120396 0.2794)
			(end -0.12065 0.2794)
			(stroke
				(width 0.1)
				(type default)
			)
			(layer "F.Fab")
		)
		(fp_line
			(start 0.120396 0.3048)
			(end 0.120396 0.2794)
			(stroke
				(width 0.1)
				(type default)
			)
			(layer "F.Fab")
		)
		(fp_line
			(start 0.12065 -0.3048)
			(end 0.67945 -0.3048)
			(stroke
				(width 0.1)
				(type default)
			)
			(layer "F.Fab")
		)
		(fp_line
			(start 0.12065 -0.2794)
			(end 0.12065 -0.3048)
			(stroke
				(width 0.1)
				(type default)
			)
			(layer "F.Fab")
		)
		(fp_line
			(start 0.67945 -0.3048)
			(end 0.67945 0.3048)
			(stroke
				(width 0.1)
				(type default)
			)
			(layer "F.Fab")
		)
		(fp_line
			(start 0.67945 0.3048)
			(end 0.120396 0.3048)
			(stroke
				(width 0.1)
				(type default)
			)
			(layer "F.Fab")
		)
		(pad "1" smd circle
			(at -0.40005 0)
			(size 0 0)
			(layers "F.Cu" "F.Mask" "F.Paste")
			(net "P3V3_AUX")
		)
		(pad "2" smd circle
			(at 0.40005 0)
			(size 0 0)
			(layers "F.Cu" "F.Mask" "F.Paste")
			(net "GND")
		)
	)
	(footprint ""
		(layer "F.Cu")
		(at 112.26546 -418.027358 90)
		(property "Reference" "R2659"
			(at 0 0 90)
			(layer "F.SilkS")
			(hide yes)
			(effects
				(font
					(size 1.27 1.27)
				)
			)
		)
		(property "Value" ""
			(at 0 0 90)
			(layer "F.Fab")
			(effects
				(font
					(size 1.27 1.27)
				)
			)
		)
		(duplicate_pad_numbers_are_jumpers no)
		(fp_line
			(start -0.33147 -0.4064)
			(end 0.31877 -0.4064)
			(stroke
				(width 0.1524)
				(type default)
			)
			(layer "F.SilkS")
		)
		(fp_line
			(start 0.7874 -0.01524)
			(end 0.7874 0.4064)
			(stroke
				(width 0.1524)
				(type default)
			)
			(layer "F.SilkS")
		)
		(fp_line
			(start 0.7874 0.4064)
			(end -0.7874 0.4064)
			(stroke
				(width 0.1524)
				(type default)
			)
			(layer "F.SilkS")
		)
		(fp_line
			(start -0.7874 0.4064)
			(end -0.7874 -0.0254)
			(stroke
				(width 0.1524)
				(type default)
			)
			(layer "F.SilkS")
		)
		(fp_line
			(start -0.12065 -0.305054)
			(end -0.12065 -0.2794)
			(stroke
				(width 0.1)
				(type default)
			)
			(layer "F.Fab")
		)
		(fp_line
			(start -0.67945 -0.305054)
			(end -0.12065 -0.305054)
			(stroke
				(width 0.1)
				(type default)
			)
			(layer "F.Fab")
		)
		(fp_line
			(start 0.67945 -0.3048)
			(end 0.67945 0.3048)
			(stroke
				(width 0.1)
				(type default)
			)
			(layer "F.Fab")
		)
		(fp_line
			(start 0.12065 -0.3048)
			(end 0.67945 -0.3048)
			(stroke
				(width 0.1)
				(type default)
			)
			(layer "F.Fab")
		)
		(fp_line
			(start 0.12065 -0.2794)
			(end 0.12065 -0.3048)
			(stroke
				(width 0.1)
				(type default)
			)
			(layer "F.Fab")
		)
		(fp_line
			(start -0.12065 -0.2794)
			(end 0.12065 -0.2794)
			(stroke
				(width 0.1)
				(type default)
			)
			(layer "F.Fab")
		)
		(fp_line
			(start 0.120396 0.2794)
			(end -0.12065 0.2794)
			(stroke
				(width 0.1)
				(type default)
			)
			(layer "F.Fab")
		)
		(fp_line
			(start -0.12065 0.2794)
			(end -0.12065 0.3048)
			(stroke
				(width 0.1)
				(type default)
			)
			(layer "F.Fab")
		)
		(fp_line
			(start 0.67945 0.3048)
			(end 0.120396 0.3048)
			(stroke
				(width 0.1)
				(type default)
			)
			(layer "F.Fab")
		)
		(fp_line
			(start 0.120396 0.3048)
			(end 0.120396 0.2794)
			(stroke
				(width 0.1)
				(type default)
			)
			(layer "F.Fab")
		)
		(fp_line
			(start -0.12065 0.3048)
			(end -0.67945 0.3048)
			(stroke
				(width 0.1)
				(type default)
			)
			(layer "F.Fab")
		)
		(fp_line
			(start -0.67945 0.3048)
			(end -0.67945 -0.305054)
			(stroke
				(width 0.1)
				(type default)
			)
			(layer "F.Fab")
		)
		(pad "1" smd circle
			(at -0.40005 0 90)
			(size 0 0)
			(layers "F.Cu" "F.Mask" "F.Paste")
			(net "CLK_100M_SWB_R_DP")
		)
		(pad "2" smd circle
			(at 0.40005 0 90)
			(size 0 0)
			(layers "F.Cu" "F.Mask" "F.Paste")
			(net "CLK_100M_SWB_DP")
		)
	)
	(footprint ""
		(layer "F.Cu")
		(at 403.37613 -408.517344 -90)
		(property "Reference" "C890"
			(at 0 0 270)
			(layer "F.SilkS")
			(hide yes)
			(effects
				(font
					(size 1.27 1.27)
				)
			)
		)
		(property "Value" ""
			(at 0 0 270)
			(layer "F.Fab")
			(effects
				(font
					(size 1.27 1.27)
				)
			)
		)
		(duplicate_pad_numbers_are_jumpers no)
		(fp_line
			(start -0.299974 0.150114)
			(end -0.299974 -0.150114)
			(stroke
				(width 0.1)
				(type default)
			)
			(layer "F.Fab")
		)
		(fp_line
			(start 0.299974 0.150114)
			(end -0.299974 0.150114)
			(stroke
				(width 0.1)
				(type default)
			)
			(layer "F.Fab")
		)
		(fp_line
			(start -0.299974 -0.150114)
			(end 0.299974 -0.150114)
			(stroke
				(width 0.1)
				(type default)
			)
			(layer "F.Fab")
		)
		(fp_line
			(start 0.299974 -0.150114)
			(end 0.299974 0.150114)
			(stroke
				(width 0.1)
				(type default)
			)
			(layer "F.Fab")
		)
		(pad "1" smd rect
			(at -0.2667 0 270)
			(size 0.3048 0.381)
			(layers "F.Cu" "F.Mask" "F.Paste")
			(net "P5E_CPU0_PE3_TX_C_DN<5>")
		)
		(pad "2" smd rect
			(at 0.2667 0 270)
			(size 0.3048 0.381)
			(layers "F.Cu" "F.Mask" "F.Paste")
			(net "P5E_CPU0_PE3_TX_DN<5>")
		)
	)
	(footprint ""
		(layer "F.Cu")
		(at 159.317944 -81.902554 90)
		(property "Reference" "R3125"
			(at 0 0 90)
			(layer "F.SilkS")
			(hide yes)
			(effects
				(font
					(size 1.27 1.27)
				)
			)
		)
		(property "Value" ""
			(at 0 0 90)
			(layer "F.Fab")
			(effects
				(font
					(size 1.27 1.27)
				)
			)
		)
		(duplicate_pad_numbers_are_jumpers no)
		(fp_line
			(start 0.7874 -0.4064)
			(end 0.7874 0.4064)
			(stroke
				(width 0.1524)
				(type default)
			)
			(layer "F.SilkS")
		)
		(fp_line
			(start -0.7874 -0.4064)
			(end 0.7874 -0.4064)
			(stroke
				(width 0.1524)
				(type default)
			)
			(layer "F.SilkS")
		)
		(fp_line
			(start 0.7874 0.4064)
			(end -0.7874 0.4064)
			(stroke
				(width 0.1524)
				(type default)
			)
			(layer "F.SilkS")
		)
		(fp_line
			(start -0.7874 0.4064)
			(end -0.7874 -0.4064)
			(stroke
				(width 0.1524)
				(type default)
			)
			(layer "F.SilkS")
		)
		(fp_line
			(start -0.12065 -0.305054)
			(end -0.12065 -0.2794)
			(stroke
				(width 0.1)
				(type default)
			)
			(layer "F.Fab")
		)
		(fp_line
			(start -0.67945 -0.305054)
			(end -0.12065 -0.305054)
			(stroke
				(width 0.1)
				(type default)
			)
			(layer "F.Fab")
		)
		(fp_line
			(start 0.67945 -0.3048)
			(end 0.67945 0.3048)
			(stroke
				(width 0.1)
				(type default)
			)
			(layer "F.Fab")
		)
		(fp_line
			(start 0.12065 -0.3048)
			(end 0.67945 -0.3048)
			(stroke
				(width 0.1)
				(type default)
			)
			(layer "F.Fab")
		)
		(fp_line
			(start 0.12065 -0.2794)
			(end 0.12065 -0.3048)
			(stroke
				(width 0.1)
				(type default)
			)
			(layer "F.Fab")
		)
		(fp_line
			(start -0.12065 -0.2794)
			(end 0.12065 -0.2794)
			(stroke
				(width 0.1)
				(type default)
			)
			(layer "F.Fab")
		)
		(fp_line
			(start 0.120396 0.2794)
			(end -0.12065 0.2794)
			(stroke
				(width 0.1)
				(type default)
			)
			(layer "F.Fab")
		)
		(fp_line
			(start -0.12065 0.2794)
			(end -0.12065 0.3048)
			(stroke
				(width 0.1)
				(type default)
			)
			(layer "F.Fab")
		)
		(fp_line
			(start 0.67945 0.3048)
			(end 0.120396 0.3048)
			(stroke
				(width 0.1)
				(type default)
			)
			(layer "F.Fab")
		)
		(fp_line
			(start 0.120396 0.3048)
			(end 0.120396 0.2794)
			(stroke
				(width 0.1)
				(type default)
			)
			(layer "F.Fab")
		)
		(fp_line
			(start -0.12065 0.3048)
			(end -0.67945 0.3048)
			(stroke
				(width 0.1)
				(type default)
			)
			(layer "F.Fab")
		)
		(fp_line
			(start -0.67945 0.3048)
			(end -0.67945 -0.305054)
			(stroke
				(width 0.1)
				(type default)
			)
			(layer "F.Fab")
		)
		(pad "1" smd circle
			(at -0.40005 0 90)
			(size 0 0)
			(layers "F.Cu" "F.Mask" "F.Paste")
			(net "SMB_S3M_CPU1_PIROM_3V3AUX_SCL_R")
		)
		(pad "2" smd circle
			(at 0.40005 0 90)
			(size 0 0)
			(layers "F.Cu" "F.Mask" "F.Paste")
			(net "SMB_S3M_CPU1_PIROM_3V3AUX_SCL")
		)
	)
)
